FILE_TYPE = MULTI_PHYS_TABLE;

PART 'LM4040AIM3X25NOPB'

{========================================================================================}
:VALUE                  | PART_TYPE | MATERIAL | PART_NUMBER    = STANDARD    | LIFECYCLE     | PART_NUMBER   | JEDEC_TYPE           | DESCRIPTION                               | MANUFTR | MANUF_PN               | RD_CMPLS_LVL | CMPLS_LVL | FROM_PJ       | CLASS | DIP_SMD | DATA                           | EE_CHECK_LIST | FP_ECN | PSL | CREATOR | STATUS | CREATEDAY  ;
{========================================================================================}
 'LM4040AIM3X-2.5/NOPB' | 'SMLF'    | 'IC'     | 'AL404025013'(!) = ''               | ''               | 'AL404025013' |'SOT23_123_2-92X1-3'| 'IC OTHER(3P)LM4040AIM3X-2.5/NOPB(SOT23)' | 'TIC'   | 'LM4040AIM3X-2.5/NOPB' | 'EP(V1)'     | ''        | 'T6MB-JOSEPH' | 'IC'  | ''      | 'TIC_LM4040-N_LM4040-N-Q1.pdf' | ''            | ''     | ''  | ''      | ''     | '20150917'
 'LM4040AIM3X-2.5/NOPB' | 'SMLF'    | 'EMPTY'  | 'AL404025013'(!) = ''               | ''               | 'AL404025013' |'SOT23_123_2-92X1-3'| 'IC OTHER(3P)LM4040AIM3X-2.5/NOPB(SOT23)' | 'TIC'   | 'LM4040AIM3X-2.5/NOPB' | 'EP(V1)'     | ''        | 'T6MB-JOSEPH' | 'IC'  | ''      | 'TIC_LM4040-N_LM4040-N-Q1.pdf' | ''            | ''     | ''  | ''      | ''     | '20150917'

END_PART

END.

